# TIMECARD (Time Appliance Project (Time Card)) — schematic netlist excerpt (pin names and nets, part order shuffled) for the footprints in the layout excerpt that follows; sources: Cadence DE-HDL packaged netlist, KiCad conversion of R4006-B0001-02_R01.brd

C29  CAPACITOR  0.1UF 10V 10%  pkg SMC_0402R_H022  page 32 : \1\ = R_XP5R0V_EN ; \2\ = SG
R236  RESISTOR  4.7KOHM 1%  pkg SMC_0402R_H016  page 15 : \1\ = VDD3V3_OSC_125M ; \2\ = CLK_125M_OE

(kicad_pcb
	(version 20260206)
	(generator "pcbnew")
	(generator_version "10.0")
	(general
		(thickness 1.6)
		(legacy_teardrops no)
	)
	(paper "A4")
	(title_block
		(title "timecard-production-celestica-r4006 — R4006-B0001-02_R01.brd")
		(comment 1 "Time Appliance Project (Time Card) / footprints 527-528 of 1113")
	)
	(layers
		(0 "F.Cu" signal "TOP")
		(4 "In1.Cu" signal "L02_GND1")
		(6 "In2.Cu" signal "L03_SIG1")
		(8 "In3.Cu" signal "L04_GND2")
		(10 "In4.Cu" signal "L05_VCC1")
		(12 "In5.Cu" signal "L06_VCC2")
		(14 "In6.Cu" signal "L07_GND3")
		(16 "In7.Cu" signal "L08_SIG2")
		(18 "In8.Cu" signal "L09_GND4")
		(2 "B.Cu" signal "BOTTOM")
		(9 "F.Adhes" user "F.Adhesive")
		(11 "B.Adhes" user "B.Adhesive")
		(13 "F.Paste" user "Package Geometry/Pastemask Top")
		(15 "B.Paste" user "Package Geometry/Pastemask Bottom")
		(5 "F.SilkS" user "Ref Des/Silkscreen Top")
		(7 "B.SilkS" user "Ref Des/Silkscreen Bottom")
		(1 "F.Mask" user "Board Geometry/Soldermask Top")
		(3 "B.Mask" user "Board Geometry/Soldermask Bottom")
		(17 "Dwgs.User" user "User.Drawings")
		(19 "Cmts.User" user "User.Comments")
		(21 "Eco1.User" user "User.Eco1")
		(23 "Eco2.User" user "User.Eco2")
		(25 "Edge.Cuts" user "Board Geometry/Outline")
		(27 "Margin" user)
		(31 "F.CrtYd" user "Package Geometry/Place Bound Top")
		(29 "B.CrtYd" user "Package Geometry/Place Bound Bottom")
		(35 "F.Fab" user "Ref Des/Assembly Top")
		(33 "B.Fab" user "Ref Des/Assembly Bottom")
	)
	(footprint ""
		(layer "F.Cu")
		(at 36.9824 -100.2284 180)
		(property "Reference" "C29"
			(at 4.064 1.86563 0)
			(unlocked yes)
			(layer "F.SilkS")
			(effects
				(font
					(size 0.7874 0.5842)
					(thickness 0.1524)
				)
			)
		)
		(property "Value" "VAL*"
			(at 0.0762 2.067306 180)
			(unlocked yes)
			(layer "F.Fab")
			(hide yes)
			(effects
				(font
					(size 0.7874 0.5842)
					(thickness 0.1524)
				)
			)
		)
		(property "Device Type" "CAPACITOR-G105-0B104-CK,0.1UF,A"
			(at 0.0508 1.127506 180)
			(unlocked yes)
			(layer "F.Fab")
			(hide yes)
			(effects
				(font
					(size 0.7874 0.5842)
					(thickness 0.1524)
				)
			)
		)
		(property "User Part Number" "PARTNUM*"
			(at 0.1016 4.023106 180)
			(unlocked yes)
			(layer "Cmts.User")
			(hide yes)
			(effects
				(font
					(size 0.7874 0.5842)
					(thickness 0.1524)
				)
			)
		)
		(property "Tolerance" "TOL*"
			(at 0.0762 3.032506 180)
			(unlocked yes)
			(layer "Cmts.User")
			(hide yes)
			(effects
				(font
					(size 0.7874 0.5842)
					(thickness 0.1524)
				)
			)
		)
		(duplicate_pad_numbers_are_jumpers no)
		(fp_line
			(start 1.143 0.5588)
			(end 1.143 -0.5588)
			(stroke
				(width 0.1)
				(type default)
			)
			(layer "F.SilkS")
		)
		(fp_line
			(start 1.143 -0.5588)
			(end -1.143 -0.5588)
			(stroke
				(width 0.1)
				(type default)
			)
			(layer "F.SilkS")
		)
		(fp_line
			(start -1.143 0.5588)
			(end 1.143 0.5588)
			(stroke
				(width 0.1)
				(type default)
			)
			(layer "F.SilkS")
		)
		(fp_line
			(start -1.143 -0.5588)
			(end -1.143 0.5588)
			(stroke
				(width 0.1)
				(type default)
			)
			(layer "F.SilkS")
		)
		(fp_rect
			(start -1.143 0.5588)
			(end 1.143 -0.5588)
			(stroke
				(width 0)
				(type default)
			)
			(fill no)
			(layer "F.CrtYd")
		)
		(fp_line
			(start 0.508 0.3048)
			(end 0.508 -0.3048)
			(stroke
				(width 0.1)
				(type default)
			)
			(layer "F.Fab")
		)
		(fp_line
			(start 0.508 -0.3048)
			(end -0.508 -0.3048)
			(stroke
				(width 0.1)
				(type default)
			)
			(layer "F.Fab")
		)
		(fp_line
			(start -0.508 0.3048)
			(end 0.508 0.3048)
			(stroke
				(width 0.1)
				(type default)
			)
			(layer "F.Fab")
		)
		(fp_line
			(start -0.508 -0.3048)
			(end -0.508 0.3048)
			(stroke
				(width 0.1)
				(type default)
			)
			(layer "F.Fab")
		)
		(pad "1" smd rect
			(at -0.5334 0 180)
			(size 0.7112 0.6096)
			(layers "F.Cu" "F.Mask" "F.Paste")
			(net "R_XP5R0V_EN")
		)
		(pad "2" smd rect
			(at 0.5334 0 180)
			(size 0.7112 0.6096)
			(layers "F.Cu" "F.Mask" "F.Paste")
			(net "SG")
		)
		(zone
			(layer "F.Cu")
			(hatch none 0.5)
			(connect_pads
				(clearance 0)
			)
			(min_thickness 0.25)
			(keepout
				(tracks allowed)
				(vias not_allowed)
				(pads allowed)
				(copperpour not_allowed)
				(footprints allowed)
			)
			(placement
				(enabled no)
				(sheetname "")
			)
			(fill
				(thermal_gap 0.5)
				(thermal_bridge_width 0.5)
				(island_removal_mode 0)
			)
			(polygon
				(pts
					(xy 37.0586 -100.5332) (xy 36.9062 -100.5332) (xy 36.9062 -99.9236) (xy 37.0586 -99.9236)
				)
			)
		)
	)
	(footprint ""
		(layer "F.Cu")
		(at 95.758 -22.733 -90)
		(property "Reference" "R236"
			(at 2.794 0.08763 90)
			(unlocked yes)
			(layer "F.SilkS")
			(effects
				(font
					(size 0.7874 0.5842)
					(thickness 0.1524)
				)
			)
		)
		(property "Value" "VAL*"
			(at 0.02032 2.13233 270)
			(unlocked yes)
			(layer "F.Fab")
			(hide yes)
			(effects
				(font
					(size 0.7874 0.5842)
					(thickness 0.1524)
				)
			)
		)
		(property "Device Type" "RESISTOR-G155-14701-01,4.7KOHMA"
			(at 0.008382 1.210564 270)
			(unlocked yes)
			(layer "F.Fab")
			(hide yes)
			(effects
				(font
					(size 0.7874 0.5842)
					(thickness 0.1524)
				)
			)
		)
		(property "User Part Number" "PARTNUM*"
			(at 0.02032 4.024884 270)
			(unlocked yes)
			(layer "Cmts.User")
			(hide yes)
			(effects
				(font
					(size 0.7874 0.5842)
					(thickness 0.1524)
				)
			)
		)
		(property "Tolerance" "TOL*"
			(at 0.044704 3.05435 270)
			(unlocked yes)
			(layer "Cmts.User")
			(hide yes)
			(effects
				(font
					(size 0.7874 0.5842)
					(thickness 0.1524)
				)
			)
		)
		(duplicate_pad_numbers_are_jumpers no)
		(fp_line
			(start -1.143 0.5588)
			(end 1.143 0.5588)
			(stroke
				(width 0.1)
				(type default)
			)
			(layer "F.SilkS")
		)
		(fp_line
			(start 1.143 0.5588)
			(end 1.143 -0.5588)
			(stroke
				(width 0.1)
				(type default)
			)
			(layer "F.SilkS")
		)
		(fp_line
			(start -1.143 -0.5588)
			(end -1.143 0.5588)
			(stroke
				(width 0.1)
				(type default)
			)
			(layer "F.SilkS")
		)
		(fp_line
			(start 1.143 -0.5588)
			(end -1.143 -0.5588)
			(stroke
				(width 0.1)
				(type default)
			)
			(layer "F.SilkS")
		)
		(fp_rect
			(start 1.143 0.5588)
			(end -1.143 -0.5588)
			(stroke
				(width 0)
				(type default)
			)
			(fill no)
			(layer "F.CrtYd")
		)
		(fp_line
			(start -0.508 0.3048)
			(end 0.508 0.3048)
			(stroke
				(width 0.1)
				(type default)
			)
			(layer "F.Fab")
		)
		(fp_line
			(start 0.508 0.3048)
			(end 0.508 -0.3048)
			(stroke
				(width 0.1)
				(type default)
			)
			(layer "F.Fab")
		)
		(fp_line
			(start -0.508 -0.3048)
			(end -0.508 0.3048)
			(stroke
				(width 0.1)
				(type default)
			)
			(layer "F.Fab")
		)
		(fp_line
			(start 0.508 -0.3048)
			(end -0.508 -0.3048)
			(stroke
				(width 0.1)
				(type default)
			)
			(layer "F.Fab")
		)
		(pad "1" smd rect
			(at -0.5334 0 270)
			(size 0.7112 0.6096)
			(layers "F.Cu" "F.Mask" "F.Paste")
			(net "VDD3V3_OSC_125M")
		)
		(pad "2" smd rect
			(at 0.5334 0 270)
			(size 0.7112 0.6096)
			(layers "F.Cu" "F.Mask" "F.Paste")
			(net "CLK_125M_OE")
		)
		(zone
			(layer "F.Cu")
			(hatch none 0.5)
			(connect_pads
				(clearance 0)
			)
			(min_thickness 0.25)
			(keepout
				(tracks allowed)
				(vias not_allowed)
				(pads allowed)
				(copperpour not_allowed)
				(footprints allowed)
			)
			(placement
				(enabled no)
				(sheetname "")
			)
			(fill
				(thermal_gap 0.5)
				(thermal_bridge_width 0.5)
				(island_removal_mode 0)
			)
			(polygon
				(pts
					(xy 95.4532 -22.6568) (xy 96.0628 -22.6568) (xy 96.0628 -22.8092) (xy 95.4532 -22.8092)
				)
			)
		)
	)
)
